#ISCELL
  mstr_misc dns *
  *
#ISCELL
  pure_quanta quanta_title_block_c *
  *
#ISCELL
  pure_quanta_power vcc_core *
  page182_i1
#ISCELL
  standard offpage *
  page182_i10
#ISCELL
  standard offpage *
  page182_i11
#ISCELL
  standard offpage *
  page182_i12
#CELL
  pure_quanta q_res *
  page182_i13
#ISCELL
  pure_quanta_power universal_gnd *
  page182_i14
#CELL
  pure_quanta q_res *
  page182_i15
#CELL
  pure_quanta q_res *
  page182_i16
#ISCELL
  pure_quanta_power universal_gnd *
  page182_i17
#CELL
  pure_quanta q_res *
  page182_i18
#ISCELL
  pure_quanta_power universal_gnd *
  page182_i19
#CELL
  pure_quanta q_res *
  page182_i2
#CELL
  pure_quanta q_cap *
  page182_i20
#ISCELL
  pure_quanta_power universal_gnd *
  page182_i21
#CELL
  pure_quanta q_res *
  page182_i22
#ISCELL
  pure_quanta_power universal_gnd *
  page182_i23
#CELL
  pure_quanta raa229621gnpha0 *
  page182_i24
#CELL
  pure_quanta q_res *
  page182_i25
#ISCELL
  pure_quanta_power vcc_core *
  page182_i26
#ISCELL
  pure_quanta_power universal_gnd *
  page182_i27
#CELL
  pure_quanta q_res *
  page182_i28
#CELL
  pure_quanta q_cap *
  page182_i29
#ISCELL
  pure_quanta_power universal_gnd *
  page182_i3
#CELL
  pure_quanta q_res *
  page182_i30
#ISCELL
  pure_quanta_power vcc_core *
  page182_i31
#ISCELL
  standard offpage *
  page182_i32
#ISCELL
  standard offpage *
  page182_i33
#ISCELL
  standard offpage *
  page182_i34
#ISCELL
  standard offpage *
  page182_i35
#ISCELL
  standard offpage *
  page182_i36
#ISCELL
  pure_quanta_power vcc_core *
  page182_i37
#CELL
  pure_quanta q_res *
  page182_i38
#CELL
  pure_quanta q_res *
  page182_i39
#CELL
  pure_quanta q_cap *
  page182_i4
#CELL
  pure_quanta q_res *
  page182_i40
#CELL
  pure_quanta q_res *
  page182_i41
#ISCELL
  pure_quanta_power universal_gnd *
  page182_i42
#CELL
  pure_quanta q_res *
  page182_i43
#CELL
  pure_quanta q_res *
  page182_i44
#CELL
  pure_quanta q_cap *
  page182_i45
#ISCELL
  pure_quanta_power universal_gnd *
  page182_i46
#CELL
  pure_quanta q_cap *
  page182_i47
#ISCELL
  pure_quanta_power universal_gnd *
  page182_i48
#ISCELL
  pure_quanta_power universal_gnd *
  page182_i49
#ISCELL
  pure_quanta_power universal_gnd *
  page182_i5
#CELL
  pure_quanta q_cap *
  page182_i50
#ISCELL
  standard offpage *
  page182_i51
#CELL
  pure_quanta q_res *
  page182_i52
#CELL
  pure_quanta q_res *
  page182_i53
#ISCELL
  pure_quanta_power universal_gnd *
  page182_i54
#ISCELL
  pure_quanta_power universal_gnd *
  page182_i55
#ISCELL
  pure_quanta_power universal_gnd *
  page182_i56
#CELL
  pure_quanta q_res *
  page182_i57
#CELL
  pure_quanta q_res *
  page182_i58
#CELL
  pure_quanta q_res *
  page182_i59
#CELL
  pure_quanta q_res *
  page182_i6
#CELL
  pure_quanta q_res *
  page182_i60
#CELL
  pure_quanta q_res *
  page182_i61
#ISCELL
  pure_quanta_power universal_gnd *
  page182_i62
#ISCELL
  pure_quanta_power universal_gnd *
  page182_i63
#ISCELL
  pure_quanta_power universal_gnd *
  page182_i64
#ISCELL
  pure_quanta_power universal_gnd *
  page182_i65
#ISCELL
  pure_quanta_power universal_gnd *
  page182_i66
#CELL
  pure_quanta q_res *
  page182_i67
#CELL
  pure_quanta q_res *
  page182_i68
#ISCELL
  pure_quanta_power vcc_core *
  page182_i69
#ISCELL
  pure_quanta_power vcc_core *
  page182_i7
#ISCELL
  standard offpage *
  page182_i70
#CELL
  pure_quanta q_res *
  page182_i71
#ISCELL
  standard offpage *
  page182_i72
#ISCELL
  standard offpage *
  page182_i73
#ISCELL
  standard offpage *
  page182_i74
#ISCELL
  standard offpage *
  page182_i75
#ISCELL
  pure_quanta_power universal_gnd *
  page182_i76
#CELL
  pure_quanta q_cap *
  page182_i77
#ISCELL
  pure_quanta_power universal_gnd *
  page182_i78
#CELL
  pure_quanta q_cap *
  page182_i79
#ISCELL
  pure_quanta_power vcc_core *
  page182_i8
#CELL
  pure_quanta q_cap *
  page182_i80
#ISCELL
  pure_quanta_power universal_gnd *
  page182_i81
#CELL
  pure_quanta q_cap *
  page182_i82
#ISCELL
  pure_quanta_power universal_gnd *
  page182_i83
#ISCELL
  standard offpage *
  page182_i84
#CELL
  pure_quanta q_res *
  page182_i85
#ISCELL
  pure_quanta_power vcc_core *
  page182_i86
#ISCELL
  pure_quanta_power universal_gnd *
  page182_i87
#CELL
  pure_quanta q_cap *
  page182_i88
#CELL
  pure_quanta q_res *
  page182_i9
